# T6G (Grand Teton) — schematic netlist excerpt (pin names and nets, part order shuffled) for the footprints in the layout excerpt that follows; sources: Cadence DE-HDL packaged netlist, KiCad conversion of 04192023_DAF0TMB3IC0_F0TG_MB_C_brd_V02_OCP.brd

PU15  ISL99390FRZTR5935  ISL99390FRZ-TR5935 IC  pkg QFN21_6X5XB  page 202
  VOS  = PVDDCR_CPU1_P0_VOS3
  AGND  = GND
  VCC  = PVDDCR_CPU1_P0_VCC3
  PVCC  = PVDDCR_CPU1_P0_PVCC
  PGND1  = GND
  GL1  = NC_PVDDCR_CPU1_P0_GL1_3
  PGND2  = GND
  SW  = SW_PVDDCR_CPU1_P0_SW3
  VIN1  = SW_P12V_AUX_PVDDCR_CPU1_P0_FLT
  VIN2  = SW_P12V_AUX_PVDDCR_CPU1_P0_FLT
  DNC  = NC_PVDDCR_CPU1_P0_DNC3
  PHASE  = SW_PVDDCR_CPU1_P0_BOOTR3
  BOOT  = SW_PVDDCR_CPU1_P0_BOOT3
  PWM  = PVDDCR_CPU1_P0_PWM3
  EN  = PVDDCR_CPU1_P0_VCC3
  TOUT_FLT  = PVDDCR_CPU1_P0_TEMP0
  LSET  = PVDDCR_CPU1_P0_LSET3
  IOUT  = PVDDCR_CPU1_P0_IMON3
  REFIN  = PVDDCR_CPU1_P0_VCCS
  PGND3  = GND
  GL2  = NC_PVDDCR_CPU1_P0_GL2_3

(kicad_pcb
	(version 20260206)
	(generator "pcbnew")
	(generator_version "10.0")
	(general
		(thickness 1.6)
		(legacy_teardrops no)
	)
	(paper "A4")
	(title_block
		(title "04192023_DAF0TMB3IC0_F0TG_MB_C_brd_V02_OCP.brd")
		(comment 1 "Grand Teton / footprints 3833-3833 of 8354")
	)
	(layers
		(0 "F.Cu" signal "TOP")
		(4 "In1.Cu" signal "GND")
		(6 "In2.Cu" signal "IN1")
		(8 "In3.Cu" signal "GND1")
		(10 "In4.Cu" signal "IN2")
		(12 "In5.Cu" signal "GND2")
		(14 "In6.Cu" signal "IN3")
		(16 "In7.Cu" signal "GND3")
		(18 "In8.Cu" signal "VCC")
		(20 "In9.Cu" signal "VCC1")
		(22 "In10.Cu" signal "GND4")
		(24 "In11.Cu" signal "IN4")
		(26 "In12.Cu" signal "GND5")
		(28 "In13.Cu" signal "IN5")
		(30 "In14.Cu" signal "GND6")
		(32 "In15.Cu" signal "IN6")
		(34 "In16.Cu" signal "GND7")
		(2 "B.Cu" signal "BOTTOM")
		(9 "F.Adhes" user "F.Adhesive")
		(11 "B.Adhes" user "B.Adhesive")
		(13 "F.Paste" user "Package Geometry/Pastemask Top")
		(15 "B.Paste" user "Package Geometry/Pastemask Bottom")
		(5 "F.SilkS" user "Ref Des/Silkscreen Top")
		(7 "B.SilkS" user "Ref Des/Silkscreen Bottom")
		(1 "F.Mask" user "Board Geometry/Soldermask Top")
		(3 "B.Mask" user "Board Geometry/Soldermask Bottom")
		(17 "Dwgs.User" user "User.Drawings")
		(19 "Cmts.User" user "User.Comments")
		(21 "Eco1.User" user "User.Eco1")
		(23 "Eco2.User" user "User.Eco2")
		(25 "Edge.Cuts" user "Board Geometry/Outline")
		(27 "Margin" user)
		(31 "F.CrtYd" user "Package Geometry/Place Bound Top")
		(29 "B.CrtYd" user "Package Geometry/Place Bound Bottom")
		(35 "F.Fab" user "Ref Des/Assembly Top")
		(33 "B.Fab" user "Ref Des/Assembly Bottom")
	)
	(footprint ""
		(layer "F.Cu")
		(at 318.34582 -334.995266)
		(property "Reference" "PU15"
			(at 3.34518 -7.624064 0)
			(unlocked yes)
			(layer "F.SilkS")
			(effects
				(font
					(size 0.7874 0.5842)
					(thickness 0.1524)
				)
				(justify left)
			)
		)
		(property "Value" ""
			(at 0 0 0)
			(layer "F.Fab")
			(effects
				(font
					(size 1.27 1.27)
				)
			)
		)
		(duplicate_pad_numbers_are_jumpers no)
		(fp_line
			(start -2.500122 -2.999994)
			(end -2.24409 -2.999994)
			(stroke
				(width 0.1524)
				(type default)
			)
			(layer "F.SilkS")
		)
		(fp_line
			(start -2.500122 -2.529078)
			(end -2.500122 -2.999994)
			(stroke
				(width 0.1524)
				(type default)
			)
			(layer "F.SilkS")
		)
		(fp_line
			(start -2.500122 0.6604)
			(end -2.500122 0.229108)
			(stroke
				(width 0.1524)
				(type default)
			)
			(layer "F.SilkS")
		)
		(fp_line
			(start -2.500122 2.999994)
			(end -2.500122 2.339594)
			(stroke
				(width 0.1524)
				(type default)
			)
			(layer "F.SilkS")
		)
		(fp_line
			(start -2.2987 2.999994)
			(end -2.500122 2.999994)
			(stroke
				(width 0.1524)
				(type default)
			)
			(layer "F.SilkS")
		)
		(fp_line
			(start 2.31394 -2.999994)
			(end 2.500122 -2.999994)
			(stroke
				(width 0.1524)
				(type default)
			)
			(layer "F.SilkS")
		)
		(fp_line
			(start 2.500122 -2.999994)
			(end 2.500122 -2.44348)
			(stroke
				(width 0.1524)
				(type default)
			)
			(layer "F.SilkS")
		)
		(fp_line
			(start 2.500122 2.339594)
			(end 2.500122 2.999994)
			(stroke
				(width 0.1524)
				(type default)
			)
			(layer "F.SilkS")
		)
		(fp_line
			(start 2.500122 2.999994)
			(end 2.2987 2.999994)
			(stroke
				(width 0.1524)
				(type default)
			)
			(layer "F.SilkS")
		)
		(fp_poly
			(pts
				(xy -2.780792 -2.420112) (xy -3.4544 -2.644648) (xy -3.005328 -3.09372)
			)
			(stroke
				(width 0)
				(type default)
			)
			(fill yes)
			(layer "F.SilkS")
		)
		(fp_line
			(start -2.500122 -2.999994)
			(end 2.500122 -2.999994)
			(stroke
				(width 0.1)
				(type default)
			)
			(layer "F.Fab")
		)
		(fp_line
			(start -2.500122 2.999994)
			(end -2.500122 -2.999994)
			(stroke
				(width 0.1)
				(type default)
			)
			(layer "F.Fab")
		)
		(fp_line
			(start 2.500122 -2.999994)
			(end 2.500122 2.999994)
			(stroke
				(width 0.1)
				(type default)
			)
			(layer "F.Fab")
		)
		(fp_line
			(start 2.500122 2.999994)
			(end -2.500122 2.999994)
			(stroke
				(width 0.1)
				(type default)
			)
			(layer "F.Fab")
		)
		(fp_poly
			(pts
				(xy -4.218432 -2.783078) (xy -4.218432 -1.767078) (xy -3.202432 -2.275078)
			)
			(stroke
				(width 0)
				(type default)
			)
			(fill yes)
			(layer "F.Fab")
		)
		(pad "1" smd rect
			(at -2.400046 -2.275078 90)
			(size 0.2286 0.6096)
			(layers "F.Cu" "F.Mask" "F.Paste")
			(net "PVDDCR_CPU1_P0_VOS3")
		)
		(pad "2" smd rect
			(at -2.400046 -1.82499 90)
			(size 0.2286 0.6096)
			(layers "F.Cu" "F.Mask" "F.Paste")
			(net "GND")
		)
		(pad "3" smd rect
			(at -2.400046 -1.374902 90)
			(size 0.2286 0.6096)
			(layers "F.Cu" "F.Mask" "F.Paste")
			(net "PVDDCR_CPU1_P0_VCC3")
		)
		(pad "4" smd rect
			(at -2.400046 -0.925068 90)
			(size 0.2286 0.6096)
			(layers "F.Cu" "F.Mask" "F.Paste")
			(net "PVDDCR_CPU1_P0_PVCC")
		)
		(pad "5" smd rect
			(at -2.400046 -0.47498 90)
			(size 0.2286 0.6096)
			(layers "F.Cu" "F.Mask" "F.Paste")
			(net "GND")
		)
		(pad "6" smd rect
			(at -2.400046 -0.024892 90)
			(size 0.2286 0.6096)
			(layers "F.Cu" "F.Mask" "F.Paste")
			(net "NC_PVDDCR_CPU1_P0_GL1_3")
		)
		(pad "7_9-20_24" smd circle
			(at 0 1.150112 90)
			(size 0 0)
			(layers "F.Cu" "F.Mask" "F.Paste")
			(net "GND")
		)
		(pad "10_19" smd rect
			(at 0 2.899918 90)
			(size 0.6096 4.318)
			(layers "F.Cu" "F.Mask" "F.Paste")
			(net "SW_PVDDCR_CPU1_P0_SW3")
		)
		(pad "25_29" smd rect
			(at 1.549908 -1.279906 270)
			(size 2.0574 2.3114)
			(layers "F.Cu" "F.Mask" "F.Paste")
			(net "SW_P12V_AUX_PVDDCR_CPU1_P0_FLT")
		)
		(pad "30" smd rect
			(at 2.05994 -2.899918)
			(size 0.2286 0.6096)
			(layers "F.Cu" "F.Mask" "F.Paste")
			(net "SW_P12V_AUX_PVDDCR_CPU1_P0_FLT")
		)
		(pad "31" smd rect
			(at 1.610106 -2.899918)
			(size 0.2286 0.6096)
			(layers "F.Cu" "F.Mask" "F.Paste")
			(net "NC_PVDDCR_CPU1_P0_DNC3")
		)
		(pad "32" smd rect
			(at 1.160018 -2.899918)
			(size 0.2286 0.6096)
			(layers "F.Cu" "F.Mask" "F.Paste")
			(net "SW_PVDDCR_CPU1_P0_BOOTR3")
		)
		(pad "33" smd rect
			(at 0.70993 -2.899918)
			(size 0.2286 0.6096)
			(layers "F.Cu" "F.Mask" "F.Paste")
			(net "SW_PVDDCR_CPU1_P0_BOOT3")
		)
		(pad "34" smd rect
			(at 0.260096 -2.899918)
			(size 0.2286 0.6096)
			(layers "F.Cu" "F.Mask" "F.Paste")
			(net "PVDDCR_CPU1_P0_PWM3")
		)
		(pad "35" smd rect
			(at -0.189992 -2.899918)
			(size 0.2286 0.6096)
			(layers "F.Cu" "F.Mask" "F.Paste")
			(net "PVDDCR_CPU1_P0_VCC3")
		)
		(pad "36" smd rect
			(at -0.64008 -2.899918)
			(size 0.2286 0.6096)
			(layers "F.Cu" "F.Mask" "F.Paste")
			(net "PVDDCR_CPU1_P0_TEMP0")
		)
		(pad "37" smd rect
			(at -1.089914 -2.899918)
			(size 0.2286 0.6096)
			(layers "F.Cu" "F.Mask" "F.Paste")
			(net "PVDDCR_CPU1_P0_LSET3")
		)
		(pad "38" smd rect
			(at -1.540002 -2.899918)
			(size 0.2286 0.6096)
			(layers "F.Cu" "F.Mask" "F.Paste")
			(net "PVDDCR_CPU1_P0_IMON3")
		)
		(pad "39" smd rect
			(at -1.99009 -2.899918)
			(size 0.2286 0.6096)
			(layers "F.Cu" "F.Mask" "F.Paste")
			(net "PVDDCR_CPU1_P0_VCCS")
		)
		(pad "40" smd rect
			(at -0.87503 -1.27508)
			(size 1.7526 1.9558)
			(layers "F.Cu" "F.Mask" "F.Paste")
			(net "GND")
		)
		(pad "41" smd rect
			(at -1.525016 0.249936 270)
			(size 0.3048 0.4572)
			(layers "F.Cu" "F.Mask" "F.Paste")
			(net "NC_PVDDCR_CPU1_P0_GL2_3")
		)
		(zone
			(layer "F.Cu")
			(hatch none 0.5)
			(connect_pads
				(clearance 0)
			)
			(min_thickness 0.25)
			(keepout
				(tracks not_allowed)
				(vias allowed)
				(pads allowed)
				(copperpour not_allowed)
				(footprints allowed)
			)
			(placement
				(enabled no)
				(sheetname "")
			)
			(fill
				(thermal_gap 0.5)
				(thermal_bridge_width 0.5)
				(island_removal_mode 0)
			)
			(polygon
				(pts
					(xy 315.845698 -332.417674) (xy 315.845698 -332.744572) (xy 320.845942 -332.744572) (xy 320.845942 -332.418436)
					(xy 320.55562 -332.418436) (xy 320.55562 -332.450948) (xy 316.13602 -332.450948) (xy 316.13602 -332.417674)
				)
			)
		)
		(zone
			(layer "F.Cu")
			(hatch none 0.5)
			(connect_pads
				(clearance 0)
			)
			(min_thickness 0.25)
			(keepout
				(tracks not_allowed)
				(vias allowed)
				(pads allowed)
				(copperpour not_allowed)
				(footprints allowed)
			)
			(placement
				(enabled no)
				(sheetname "")
			)
			(fill
				(thermal_gap 0.5)
				(thermal_bridge_width 0.5)
				(island_removal_mode 0)
			)
			(polygon
				(pts
					(xy 318.39789 -335.241646) (xy 318.39789 -337.299046) (xy 316.54369 -337.299046) (xy 316.54369 -337.058)
					(xy 316.301374 -337.058) (xy 316.301374 -337.539584) (xy 320.226182 -337.539584) (xy 320.226182 -337.354672)
					(xy 318.689228 -337.354672) (xy 318.689228 -335.195672) (xy 320.845942 -335.195672) (xy 320.845942 -334.94599)
					(xy 318.693546 -334.94599)
				)
			)
		)
	)
)
